# T6G (Grand Teton) — schematic netlist excerpt (pin names and nets, part order shuffled) for the footprints in the layout excerpt that follows; sources: Cadence DE-HDL packaged netlist, KiCad conversion of 04192023_DAF0TMB3IC0_F0TG_MB_C_brd_V02_OCP.brd

C589  Q_CAP  22UF 4V 20% X6S  pkg C0402  page 290 : A = P1V8_CPU0_RT_1D ; B = GND

(kicad_pcb
	(version 20260206)
	(generator "pcbnew")
	(generator_version "10.0")
	(general
		(thickness 1.6)
		(legacy_teardrops no)
	)
	(paper "A4")
	(title_block
		(title "04192023_DAF0TMB3IC0_F0TG_MB_C_brd_V02_OCP.brd")
		(comment 1 "Grand Teton / footprints 238-238 of 8354")
	)
	(layers
		(0 "F.Cu" signal "TOP")
		(4 "In1.Cu" signal "GND")
		(6 "In2.Cu" signal "IN1")
		(8 "In3.Cu" signal "GND1")
		(10 "In4.Cu" signal "IN2")
		(12 "In5.Cu" signal "GND2")
		(14 "In6.Cu" signal "IN3")
		(16 "In7.Cu" signal "GND3")
		(18 "In8.Cu" signal "VCC")
		(20 "In9.Cu" signal "VCC1")
		(22 "In10.Cu" signal "GND4")
		(24 "In11.Cu" signal "IN4")
		(26 "In12.Cu" signal "GND5")
		(28 "In13.Cu" signal "IN5")
		(30 "In14.Cu" signal "GND6")
		(32 "In15.Cu" signal "IN6")
		(34 "In16.Cu" signal "GND7")
		(2 "B.Cu" signal "BOTTOM")
		(9 "F.Adhes" user "F.Adhesive")
		(11 "B.Adhes" user "B.Adhesive")
		(13 "F.Paste" user "Package Geometry/Pastemask Top")
		(15 "B.Paste" user "Package Geometry/Pastemask Bottom")
		(5 "F.SilkS" user "Ref Des/Silkscreen Top")
		(7 "B.SilkS" user "Ref Des/Silkscreen Bottom")
		(1 "F.Mask" user "Board Geometry/Soldermask Top")
		(3 "B.Mask" user "Board Geometry/Soldermask Bottom")
		(17 "Dwgs.User" user "User.Drawings")
		(19 "Cmts.User" user "User.Comments")
		(21 "Eco1.User" user "User.Eco1")
		(23 "Eco2.User" user "User.Eco2")
		(25 "Edge.Cuts" user "Board Geometry/Outline")
		(27 "Margin" user)
		(31 "F.CrtYd" user "Package Geometry/Place Bound Top")
		(29 "B.CrtYd" user "Package Geometry/Place Bound Bottom")
		(35 "F.Fab" user "Ref Des/Assembly Top")
		(33 "B.Fab" user "Ref Des/Assembly Bottom")
	)
	(footprint ""
		(layer "F.Cu")
		(at 359.520236 -394.82268 90)
		(property "Reference" "C589"
			(at 0 0 90)
			(layer "F.SilkS")
			(hide yes)
			(effects
				(font
					(size 1.27 1.27)
				)
			)
		)
		(property "Value" ""
			(at 0 0 90)
			(layer "F.Fab")
			(effects
				(font
					(size 1.27 1.27)
				)
			)
		)
		(duplicate_pad_numbers_are_jumpers no)
		(fp_line
			(start 0.7874 -0.4064)
			(end 0.7874 0.4064)
			(stroke
				(width 0.1524)
				(type default)
			)
			(layer "F.SilkS")
		)
		(fp_line
			(start -0.7874 -0.4064)
			(end 0.7874 -0.4064)
			(stroke
				(width 0.1524)
				(type default)
			)
			(layer "F.SilkS")
		)
		(fp_line
			(start 0.7874 0.4064)
			(end -0.7874 0.4064)
			(stroke
				(width 0.1524)
				(type default)
			)
			(layer "F.SilkS")
		)
		(fp_line
			(start -0.7874 0.4064)
			(end -0.7874 -0.4064)
			(stroke
				(width 0.1524)
				(type default)
			)
			(layer "F.SilkS")
		)
		(fp_line
			(start -0.12065 -0.305054)
			(end -0.12065 -0.2794)
			(stroke
				(width 0.1)
				(type default)
			)
			(layer "F.Fab")
		)
		(fp_line
			(start -0.67945 -0.305054)
			(end -0.12065 -0.305054)
			(stroke
				(width 0.1)
				(type default)
			)
			(layer "F.Fab")
		)
		(fp_line
			(start 0.67945 -0.3048)
			(end 0.67945 0.3048)
			(stroke
				(width 0.1)
				(type default)
			)
			(layer "F.Fab")
		)
		(fp_line
			(start 0.12065 -0.3048)
			(end 0.67945 -0.3048)
			(stroke
				(width 0.1)
				(type default)
			)
			(layer "F.Fab")
		)
		(fp_line
			(start 0.12065 -0.2794)
			(end 0.12065 -0.3048)
			(stroke
				(width 0.1)
				(type default)
			)
			(layer "F.Fab")
		)
		(fp_line
			(start -0.12065 -0.2794)
			(end 0.12065 -0.2794)
			(stroke
				(width 0.1)
				(type default)
			)
			(layer "F.Fab")
		)
		(fp_line
			(start 0.120396 0.2794)
			(end -0.12065 0.2794)
			(stroke
				(width 0.1)
				(type default)
			)
			(layer "F.Fab")
		)
		(fp_line
			(start -0.12065 0.2794)
			(end -0.12065 0.3048)
			(stroke
				(width 0.1)
				(type default)
			)
			(layer "F.Fab")
		)
		(fp_line
			(start 0.67945 0.3048)
			(end 0.120396 0.3048)
			(stroke
				(width 0.1)
				(type default)
			)
			(layer "F.Fab")
		)
		(fp_line
			(start 0.120396 0.3048)
			(end 0.120396 0.2794)
			(stroke
				(width 0.1)
				(type default)
			)
			(layer "F.Fab")
		)
		(fp_line
			(start -0.12065 0.3048)
			(end -0.67945 0.3048)
			(stroke
				(width 0.1)
				(type default)
			)
			(layer "F.Fab")
		)
		(fp_line
			(start -0.67945 0.3048)
			(end -0.67945 -0.305054)
			(stroke
				(width 0.1)
				(type default)
			)
			(layer "F.Fab")
		)
		(pad "1" smd circle
			(at -0.40005 0 90)
			(size 0 0)
			(layers "F.Cu" "F.Mask" "F.Paste")
			(net "P1V8_CPU0_RT_1D")
		)
		(pad "2" smd circle
			(at 0.40005 0 90)
			(size 0 0)
			(layers "F.Cu" "F.Mask" "F.Paste")
			(net "GND")
		)
	)
)
